(kicad_pcb
	(version 20241229)
	(generator "pcbnew")
	(generator_version "9.0")
	(general
		(thickness 1.711)
		(legacy_teardrops no)
	)
	(paper "A4")
	(title_block
		(title "Antmicro Baseboard for Jetson AGX Thor")
		(date "2026-02-18")
		(rev "1.1.0")
		(company "Antmicro Ltd")
		(comment 1 "www.antmicro.com")
		(comment 9 "footprints 752-756 of 1170")
	)
	(layers
		(0 "F.Cu" signal)
		(4 "In1.Cu" signal)
		(6 "In2.Cu" signal)
		(8 "In3.Cu" signal)
		(10 "In4.Cu" jumper)
		(12 "In5.Cu" signal)
		(14 "In6.Cu" signal)
		(16 "In7.Cu" signal)
		(18 "In8.Cu" signal)
		(2 "B.Cu" signal)
		(9 "F.Adhes" user "F.Adhesive")
		(11 "B.Adhes" user "B.Adhesive")
		(13 "F.Paste" user)
		(15 "B.Paste" user)
		(5 "F.SilkS" user "F.Silkscreen")
		(7 "B.SilkS" user "B.Silkscreen")
		(1 "F.Mask" user)
		(3 "B.Mask" user)
		(17 "Dwgs.User" user "User.Drawings")
		(19 "Cmts.User" user "User.Comments")
		(21 "Eco1.User" user "User.Eco1")
		(23 "Eco2.User" user "User.Eco2")
		(25 "Edge.Cuts" user)
		(27 "Margin" user)
		(31 "F.CrtYd" user "F.Courtyard")
		(29 "B.CrtYd" user "B.Courtyard")
		(35 "F.Fab" user)
		(33 "B.Fab" user)
	)
	(footprint "antmicro-footprints:R_0402_1005Metric"
		(layer "B.Cu")
		(at 212.048 76.25 -90)
		(descr "Resistor SMD 0402")
		(tags "resistor SMD 0402")
		(property "Reference" "R115"
			(at -1.25 0.648 90)
			(layer "B.SilkS")
			(effects
				(font
					(size 0.7 0.7)
					(thickness 0.15)
				)
				(justify left bottom mirror)
			)
		)
		(property "Value" "R_100k_0402"
			(at -1.011843 -1.772047 90)
			(layer "B.Fab")
			(effects
				(font
					(size 0.7 0.7)
					(thickness 0.15)
				)
				(justify left bottom mirror)
			)
		)
		(property "Datasheet" "https://www.bourns.com/docs/product-datasheets/cr.pdf"
			(at 0 0 90)
			(layer "B.Fab")
			(hide yes)
			(effects
				(font
					(size 1.27 1.27)
					(thickness 0.15)
				)
				(justify mirror)
			)
		)
		(property "Description" "SMD Chip Resistor, 100 kohm, ± 1%, 62.5 mW, 0402 [1005 Metric], Thick Film, General Purpose"
			(at 0 0 90)
			(layer "B.Fab")
			(hide yes)
			(effects
				(font
					(size 1.27 1.27)
					(thickness 0.15)
				)
				(justify mirror)
			)
		)
		(property "MPN" "CR0402-FX-1003GLF"
			(at 0 0 90)
			(unlocked yes)
			(layer "B.Fab")
			(hide yes)
			(effects
				(font
					(size 1 1)
					(thickness 0.15)
				)
				(justify mirror)
			)
		)
		(property "Manufacturer" "Bourns"
			(at 0 0 90)
			(unlocked yes)
			(layer "B.Fab")
			(hide yes)
			(effects
				(font
					(size 1 1)
					(thickness 0.15)
				)
				(justify mirror)
			)
		)
		(property "License" "Apache-2.0"
			(at 0 0 90)
			(unlocked yes)
			(layer "B.Fab")
			(hide yes)
			(effects
				(font
					(size 1 1)
					(thickness 0.15)
				)
				(justify mirror)
			)
		)
		(property "Author" "Antmicro"
			(at 0 0 90)
			(unlocked yes)
			(layer "B.Fab")
			(hide yes)
			(effects
				(font
					(size 1 1)
					(thickness 0.15)
				)
				(justify mirror)
			)
		)
		(property "Val" "100k"
			(at 0 0 90)
			(unlocked yes)
			(layer "B.Fab")
			(hide yes)
			(effects
				(font
					(size 1 1)
					(thickness 0.15)
				)
				(justify mirror)
			)
		)
		(property "Tolerance" "1%"
			(at 0 0 90)
			(unlocked yes)
			(layer "B.Fab")
			(hide yes)
			(effects
				(font
					(size 1 1)
					(thickness 0.15)
				)
				(justify mirror)
			)
		)
		(sheetname "/USB Debug, PD/")
		(sheetfile "usb_debug_pd.kicad_sch")
		(attr smd)
		(fp_rect
			(start -0.925 0.47)
			(end 0.925 -0.47)
			(stroke
				(width 0.05)
				(type default)
			)
			(fill no)
			(layer "B.CrtYd")
		)
		(fp_rect
			(start -0.5 0.25)
			(end 0.5 -0.25)
			(stroke
				(width 0.15)
				(type solid)
			)
			(fill no)
			(layer "B.Fab")
		)
		(fp_text user "License: Apache-2.0"
			(at -0.95 -5.169 90)
			(layer "B.Fab")
			(effects
				(font
					(size 0.7 0.7)
					(thickness 0.15)
				)
				(justify left bottom mirror)
			)
		)
		(fp_text user "${REFERENCE}"
			(at -0.95 -3.168 90)
			(layer "B.Fab")
			(effects
				(font
					(size 0.7 0.7)
					(thickness 0.15)
				)
				(justify left bottom mirror)
			)
		)
		(fp_text user "Author: Antmicro"
			(at -0.95 -4.169 90)
			(layer "B.Fab")
			(effects
				(font
					(size 0.7 0.7)
					(thickness 0.15)
				)
				(justify left bottom mirror)
			)
		)
		(pad "1" smd roundrect
			(at -0.48 0 270)
			(size 0.59 0.64)
			(layers "B.Cu" "B.Mask" "B.Paste")
			(roundrect_rratio 0.25)
			(net 881 "/USB Debug, PD/FTDI_CBUS_EN")
			(pintype "passive")
		)
		(pad "2" smd roundrect
			(at 0.48 0 270)
			(size 0.59 0.64)
			(layers "B.Cu" "B.Mask" "B.Paste")
			(roundrect_rratio 0.25)
			(net 334 "/USB Debug, PD/FTDI_3V3")
			(pintype "passive")
		)
	)
	(footprint "antmicro-footprints:TP_SMD_0.75mm"
		(layer "B.Cu")
		(at 146.75 63.1 -90)
		(property "Reference" "TP94"
			(at 0.5 -0.45 90)
			(layer "B.SilkS")
			(effects
				(font
					(size 0.7 0.7)
					(thickness 0.15)
				)
				(justify left bottom mirror)
			)
		)
		(property "Value" "TP_0.75mm_SMD"
			(at 0 -1.2 90)
			(layer "B.Fab")
			(effects
				(font
					(size 0.7 0.7)
					(thickness 0.15)
				)
				(justify left bottom mirror)
			)
		)
		(property "Description" "SMT test point"
			(at 0 0 90)
			(layer "B.Fab")
			(hide yes)
			(effects
				(font
					(size 1.27 1.27)
					(thickness 0.15)
				)
				(justify mirror)
			)
		)
		(property "MPN" ""
			(at 0 0 90)
			(unlocked yes)
			(layer "B.Fab")
			(hide yes)
			(effects
				(font
					(size 1 1)
					(thickness 0.15)
				)
				(justify mirror)
			)
		)
		(property "Manufacturer" ""
			(at 0 0 90)
			(unlocked yes)
			(layer "B.Fab")
			(hide yes)
			(effects
				(font
					(size 1 1)
					(thickness 0.15)
				)
				(justify mirror)
			)
		)
		(property "Author" "Antmicro"
			(at 0 0 90)
			(unlocked yes)
			(layer "B.Fab")
			(hide yes)
			(effects
				(font
					(size 1 1)
					(thickness 0.15)
				)
				(justify mirror)
			)
		)
		(property "License" "Apache-2.0"
			(at 0 0 90)
			(unlocked yes)
			(layer "B.Fab")
			(hide yes)
			(effects
				(font
					(size 1 1)
					(thickness 0.15)
				)
				(justify mirror)
			)
		)
		(sheetname "/Peripherals/")
		(sheetfile "peripherals.kicad_sch")
		(attr exclude_from_pos_files exclude_from_bom)
		(fp_circle
			(center 0 0)
			(end 0.475 0)
			(stroke
				(width 0.05)
				(type default)
			)
			(fill no)
			(layer "B.CrtYd")
		)
		(fp_text user "License: Apache-2.0"
			(at -0.4 -5.101 90)
			(layer "B.Fab")
			(effects
				(font
					(size 0.7 0.7)
					(thickness 0.15)
				)
				(justify left bottom mirror)
			)
		)
		(fp_text user "${REFERENCE}"
			(at -0.4 -2.7 90)
			(layer "B.Fab")
			(effects
				(font
					(size 0.7 0.7)
					(thickness 0.15)
				)
				(justify left bottom mirror)
			)
		)
		(fp_text user "Author: Antmicro"
			(at -0.4 -3.901 90)
			(layer "B.Fab")
			(effects
				(font
					(size 0.7 0.7)
					(thickness 0.15)
				)
				(justify left bottom mirror)
			)
		)
		(pad "1" smd circle
			(at 0 0 270)
			(size 0.75 0.75)
			(layers "B.Cu" "B.Mask")
			(net 839 "/Peripherals/I2C_CONN2_3V3")
			(pinfunction "1")
			(pintype "passive")
		)
	)
	(footprint "antmicro-footprints:Mech_Lightpipe_Bivar_SLP3-150-150-F"
		(locked yes)
		(layer "B.Cu")
		(at 232.829 65.329999 -90)
		(property "Reference" "H14"
			(at 0 1.6 90)
			(unlocked yes)
			(layer "B.SilkS")
			(effects
				(font
					(size 0.7 0.7)
					(thickness 0.15)
				)
				(justify left bottom mirror)
			)
		)
		(property "Value" "Lightpipe_Bivar_SLP3-150-150-F"
			(at 0 -6.6 90)
			(unlocked yes)
			(layer "B.Fab")
			(effects
				(font
					(size 0.7 0.7)
					(thickness 0.15)
				)
				(justify left bottom mirror)
			)
		)
		(property "Datasheet" "https://eu.mouser.com/datasheet/2/50/Bivar_SLP3_150_XXX_X_N-3318840.pdf"
			(at 0 0 90)
			(layer "B.Fab")
			(hide yes)
			(effects
				(font
					(size 1.27 1.27)
					(thickness 0.15)
				)
				(justify mirror)
			)
		)
		(property "Description" "LED Light Pipe, Rigid Board, Horizontal"
			(at 0 0 90)
			(layer "B.Fab")
			(hide yes)
			(effects
				(font
					(size 1.27 1.27)
					(thickness 0.15)
				)
				(justify mirror)
			)
		)
		(property "Manufacturer" "BIVAR"
			(at 0 0 90)
			(unlocked yes)
			(layer "B.Fab")
			(hide yes)
			(effects
				(font
					(size 1 1)
					(thickness 0.15)
				)
				(justify mirror)
			)
		)
		(property "MPN" "SLP3-150-150-F"
			(at 0 0 90)
			(unlocked yes)
			(layer "B.Fab")
			(hide yes)
			(effects
				(font
					(size 1 1)
					(thickness 0.15)
				)
				(justify mirror)
			)
		)
		(property "Author" "Antmicro"
			(at 0 0 90)
			(unlocked yes)
			(layer "B.Fab")
			(hide yes)
			(effects
				(font
					(size 1 1)
					(thickness 0.15)
				)
				(justify mirror)
			)
		)
		(property "License" "Apache-2.0"
			(at 0 0 90)
			(unlocked yes)
			(layer "B.Fab")
			(hide yes)
			(effects
				(font
					(size 1 1)
					(thickness 0.15)
				)
				(justify mirror)
			)
		)
		(sheetname "/SoM_Power/")
		(sheetfile "som_power.kicad_sch")
		(attr through_hole)
		(fp_poly
			(pts
				(xy -1.04 1.225) (xy 3.559 1.225) (xy 3.559 -5.326) (xy -1.04 -5.326)
			)
			(stroke
				(width 0.15)
				(type solid)
			)
			(fill no)
			(layer "B.SilkS")
		)
		(fp_poly
			(pts
				(xy -1.301 1.504001) (xy 3.819 1.504) (xy 3.819 -1.196) (xy -1.301 -1.196)
			)
			(stroke
				(width 0.05)
				(type solid)
			)
			(fill no)
			(layer "B.CrtYd")
		)
		(fp_poly
			(pts
				(xy -1.3 -4.196) (xy 3.819 -4.196) (xy 3.819 -5.596) (xy -1.3 -5.596)
			)
			(stroke
				(width 0.05)
				(type solid)
			)
			(fill no)
			(layer "B.CrtYd")
		)
		(fp_line
			(start 1.25 -1.8)
			(end 1.25 -2.499999)
			(stroke
				(width 0.15)
				(type solid)
			)
			(layer "B.Fab")
		)
		(fp_line
			(start 1.25 -2.499999)
			(end 1.95 -2.5)
			(stroke
				(width 0.15)
				(type solid)
			)
			(layer "B.Fab")
		)
		(fp_line
			(start 1.25 -2.499999)
			(end 1.25 -3.201)
			(stroke
				(width 0.15)
				(type solid)
			)
			(layer "B.Fab")
		)
		(fp_line
			(start 0.55 -2.5)
			(end 1.25 -2.499999)
			(stroke
				(width 0.15)
				(type solid)
			)
			(layer "B.Fab")
		)
		(fp_poly
			(pts
				(xy -0.791 -1.375999) (xy 3.309 -1.376) (xy 3.309 -3.625) (xy -0.791 -3.625001)
			)
			(stroke
				(width 0.15)
				(type solid)
			)
			(fill no)
			(layer "B.Fab")
		)
		(fp_text user "License: Apache-2.0"
			(at -7.21 -24.37 90)
			(layer "B.Fab")
			(effects
				(font
					(size 0.7 0.7)
					(thickness 0.15)
				)
				(justify left bottom mirror)
			)
		)
		(fp_text user "${REFERENCE}"
			(at -7.21 -23.17 90)
			(unlocked yes)
			(layer "B.Fab")
			(effects
				(font
					(size 0.7 0.7)
					(thickness 0.15)
				)
				(justify left bottom mirror)
			)
		)
		(fp_text user "Author: Antmicro"
			(at -7.209999 -25.57 90)
			(layer "B.Fab")
			(effects
				(font
					(size 0.7 0.7)
					(thickness 0.15)
				)
				(justify left bottom mirror)
			)
		)
		(pad "" np_thru_hole circle
			(at 0 0 270)
			(size 1.2 1.2)
			(drill 1.3)
			(layers "*.Cu" "*.Mask")
		)
		(pad "" np_thru_hole circle
			(at 2.5 0 270)
			(size 1.2 1.2)
			(drill 1.3)
			(layers "*.Cu" "*.Mask")
		)
	)
	(footprint "antmicro-footprints:C_0402_1005Metric"
		(layer "B.Cu")
		(at 207.35 131.83 -90)
		(descr "Capacitor SMD 0402")
		(tags "capacitor SMD 0402")
		(property "Reference" "C92"
			(at -1.03 0.55 90)
			(layer "B.SilkS")
			(effects
				(font
					(size 0.7 0.7)
					(thickness 0.15)
				)
				(justify left bottom mirror)
			)
		)
		(property "Value" "C_100n_0402"
			(at -1.022927 -2.155213 90)
			(layer "B.Fab")
			(effects
				(font
					(size 0.7 0.7)
					(thickness 0.15)
				)
				(justify left bottom mirror)
			)
		)
		(property "Datasheet" "https://www.murata.com/products/productdetail?partno=GRM155R61H104KE14%23"
			(at 0 0 90)
			(layer "B.Fab")
			(hide yes)
			(effects
				(font
					(size 1.27 1.27)
					(thickness 0.15)
				)
				(justify mirror)
			)
		)
		(property "Description" "SMD Multilayer Ceramic Capacitor, 0.1 µF, 50 V, 0402 [1005 Metric], ± 10%, X5R, GRM Series"
			(at 0 0 90)
			(layer "B.Fab")
			(hide yes)
			(effects
				(font
					(size 1.27 1.27)
					(thickness 0.15)
				)
				(justify mirror)
			)
		)
		(property "MPN" "GRM155R61H104KE14D"
			(at 0 0 90)
			(unlocked yes)
			(layer "B.Fab")
			(hide yes)
			(effects
				(font
					(size 1 1)
					(thickness 0.15)
				)
				(justify mirror)
			)
		)
		(property "Val" "100n"
			(at 0 0 90)
			(unlocked yes)
			(layer "B.Fab")
			(hide yes)
			(effects
				(font
					(size 1 1)
					(thickness 0.15)
				)
				(justify mirror)
			)
		)
		(property "Voltage" "50V"
			(at 0 0 90)
			(unlocked yes)
			(layer "B.Fab")
			(hide yes)
			(effects
				(font
					(size 1 1)
					(thickness 0.15)
				)
				(justify mirror)
			)
		)
		(property "Dielectric" "X5R"
			(at 0 0 90)
			(unlocked yes)
			(layer "B.Fab")
			(hide yes)
			(effects
				(font
					(size 1 1)
					(thickness 0.15)
				)
				(justify mirror)
			)
		)
		(property "Manufacturer" "Murata"
			(at 0 0 90)
			(unlocked yes)
			(layer "B.Fab")
			(hide yes)
			(effects
				(font
					(size 1 1)
					(thickness 0.15)
				)
				(justify mirror)
			)
		)
		(property "License" "Apache-2.0"
			(at 0 0 90)
			(unlocked yes)
			(layer "B.Fab")
			(hide yes)
			(effects
				(font
					(size 1 1)
					(thickness 0.15)
				)
				(justify mirror)
			)
		)
		(property "Author" "Antmicro"
			(at 0 0 90)
			(unlocked yes)
			(layer "B.Fab")
			(hide yes)
			(effects
				(font
					(size 1 1)
					(thickness 0.15)
				)
				(justify mirror)
			)
		)
		(sheetname "/USB Hub/")
		(sheetfile "usb_hub.kicad_sch")
		(attr smd)
		(fp_rect
			(start -0.925 0.47)
			(end 0.925 -0.47)
			(stroke
				(width 0.05)
				(type default)
			)
			(fill no)
			(layer "B.CrtYd")
		)
		(fp_line
			(start -0.494 0.25)
			(end 0.504 0.25)
			(stroke
				(width 0.15)
				(type solid)
			)
			(layer "B.Fab")
		)
		(fp_line
			(start 0.504 0.25)
			(end 0.504 -0.248)
			(stroke
				(width 0.15)
				(type solid)
			)
			(layer "B.Fab")
		)
		(fp_line
			(start -0.494 -0.248)
			(end -0.494 0.25)
			(stroke
				(width 0.15)
				(type solid)
			)
			(layer "B.Fab")
		)
		(fp_line
			(start 0.504 -0.248)
			(end -0.494 -0.248)
			(stroke
				(width 0.15)
				(type solid)
			)
			(layer "B.Fab")
		)
		(fp_text user "${REFERENCE}"
			(at -0.939 -4.599 90)
			(layer "B.Fab")
			(effects
				(font
					(size 0.7 0.7)
					(thickness 0.15)
				)
				(justify left bottom mirror)
			)
		)
		(fp_text user "License: Apache-2.0"
			(at -0.939 -5.799 90)
			(layer "B.Fab")
			(effects
				(font
					(size 0.7 0.7)
					(thickness 0.15)
				)
				(justify left bottom mirror)
			)
		)
		(fp_text user "Author: Antmicro"
			(at -0.939 -3.399 90)
			(layer "B.Fab")
			(effects
				(font
					(size 0.7 0.7)
					(thickness 0.15)
				)
				(justify left bottom mirror)
			)
		)
		(pad "1" smd roundrect
			(at -0.48 0 270)
			(size 0.59 0.64)
			(layers "B.Cu" "B.Mask" "B.Paste")
			(roundrect_rratio 0.25)
			(net 1 "GND")
			(pintype "passive")
		)
		(pad "2" smd roundrect
			(at 0.48 0 270)
			(size 0.59 0.64)
			(layers "B.Cu" "B.Mask" "B.Paste")
			(roundrect_rratio 0.25)
			(net 282 "+1V15")
			(pintype "passive")
		)
	)
	(footprint "antmicro-footprints:R_0402_1005Metric"
		(layer "B.Cu")
		(at 235.9 133 180)
		(descr "Resistor SMD 0402")
		(tags "resistor SMD 0402")
		(property "Reference" "R259"
			(at -3.784 -0.362 0)
			(layer "B.SilkS")
			(effects
				(font
					(size 0.7 0.7)
					(thickness 0.15)
				)
				(justify left bottom mirror)
			)
		)
		(property "Value" "R_2k2_0402"
			(at -1.011843 -1.772046 0)
			(layer "B.Fab")
			(effects
				(font
					(size 0.7 0.7)
					(thickness 0.15)
				)
				(justify left bottom mirror)
			)
		)
		(property "Datasheet" "https://www.bourns.com/docs/product-datasheets/cr.pdf"
			(at 0 0 0)
			(layer "B.Fab")
			(hide yes)
			(effects
				(font
					(size 1.27 1.27)
					(thickness 0.15)
				)
				(justify mirror)
			)
		)
		(property "Description" "SMD Chip Resistor, 2.2 kohm, ± 1%, 62.5 mW, 0402 [1005 Metric], Thick Film, General Purpose"
			(at 0 0 0)
			(layer "B.Fab")
			(hide yes)
			(effects
				(font
					(size 1.27 1.27)
					(thickness 0.15)
				)
				(justify mirror)
			)
		)
		(property "Manufacturer" "Bourns"
			(at 0 0 0)
			(unlocked yes)
			(layer "B.Fab")
			(hide yes)
			(effects
				(font
					(size 1 1)
					(thickness 0.15)
				)
				(justify mirror)
			)
		)
		(property "MPN" "CR0402-FX-2201GLF"
			(at 0 0 0)
			(unlocked yes)
			(layer "B.Fab")
			(hide yes)
			(effects
				(font
					(size 1 1)
					(thickness 0.15)
				)
				(justify mirror)
			)
		)
		(property "Val" "2k2"
			(at 0 0 0)
			(unlocked yes)
			(layer "B.Fab")
			(hide yes)
			(effects
				(font
					(size 1 1)
					(thickness 0.15)
				)
				(justify mirror)
			)
		)
		(property "License" "Apache-2.0"
			(at 0 0 0)
			(unlocked yes)
			(layer "B.Fab")
			(hide yes)
			(effects
				(font
					(size 1 1)
					(thickness 0.15)
				)
				(justify mirror)
			)
		)
		(property "Author" "Antmicro"
			(at 0 0 0)
			(unlocked yes)
			(layer "B.Fab")
			(hide yes)
			(effects
				(font
					(size 1 1)
					(thickness 0.15)
				)
				(justify mirror)
			)
		)
		(property "Tolerance" "1%"
			(at 0 0 0)
			(unlocked yes)
			(layer "B.Fab")
			(hide yes)
			(effects
				(font
					(size 1 1)
					(thickness 0.15)
				)
				(justify mirror)
			)
		)
		(sheetname "/USB Hub/")
		(sheetfile "usb_hub.kicad_sch")
		(attr smd)
		(fp_poly
			(pts
				(xy -0.925 0.47) (xy -0.925 -0.47) (xy 0.925 -0.47) (xy 0.925 0.47)
			)
			(stroke
				(width 0.05)
				(type default)
			)
			(fill no)
			(layer "B.CrtYd")
		)
		(fp_poly
			(pts
				(xy -0.5 0.25) (xy -0.5 -0.25) (xy 0.5 -0.25) (xy 0.5 0.25)
			)
			(stroke
				(width 0.15)
				(type solid)
			)
			(fill no)
			(layer "B.Fab")
		)
		(fp_text user "${REFERENCE}"
			(at -0.95 -3.168 0)
			(layer "B.Fab")
			(effects
				(font
					(size 0.7 0.7)
					(thickness 0.15)
				)
				(justify left bottom mirror)
			)
		)
		(fp_text user "Author: Antmicro"
			(at -0.95 -4.169 0)
			(layer "B.Fab")
			(effects
				(font
					(size 0.7 0.7)
					(thickness 0.15)
				)
				(justify left bottom mirror)
			)
		)
		(fp_text user "License: Apache-2.0"
			(at -0.949999 -5.169 0)
			(layer "B.Fab")
			(effects
				(font
					(size 0.7 0.7)
					(thickness 0.15)
				)
				(justify left bottom mirror)
			)
		)
		(pad "1" smd roundrect
			(at -0.48 0 180)
			(size 0.59 0.64)
			(layers "B.Cu" "B.Mask" "B.Paste")
			(roundrect_rratio 0.25)
			(net 1 "GND")
			(pintype "passive")
		)
		(pad "2" smd roundrect
			(at 0.48 0 180)
			(size 0.59 0.64)
			(layers "B.Cu" "B.Mask" "B.Paste")
			(roundrect_rratio 0.25)
			(net 1015 "/USB Hub/USBC4_ISET")
			(pintype "passive")
		)
	)
)
